# SCM (Grand Teton) — schematic netlist excerpt (pin names and nets, part order shuffled) for the footprints in the layout excerpt that follows; sources: Cadence DE-HDL packaged netlist, KiCad conversion of 12092022_DA0F0TMDCD0_F0T_Management_Board_D_brd_V3_OCP.brd

PR527  Q_RES  91K 1% CHIP  pkg 0402LF  page 51 : A = P5V_AUX_FB ; B = P5V_AUX
C227  Q_CAP  2.2UF 10V 10% X6S  pkg C0402  page 51 : A = P3V3_LDO ; B = GND

(kicad_pcb
	(version 20260206)
	(generator "pcbnew")
	(generator_version "10.0")
	(general
		(thickness 1.6)
		(legacy_teardrops no)
	)
	(paper "A4")
	(title_block
		(title "12092022_DA0F0TMDCD0_F0T_Management_Board_D_brd_V3_OCP.brd")
		(comment 1 "Grand Teton / footprints 659-660 of 1440")
	)
	(layers
		(0 "F.Cu" signal "TOP")
		(4 "In1.Cu" signal "GND")
		(6 "In2.Cu" signal "IN1")
		(8 "In3.Cu" signal "GND1")
		(10 "In4.Cu" signal "IN2")
		(12 "In5.Cu" signal "VCC")
		(14 "In6.Cu" signal "VCC1")
		(16 "In7.Cu" signal "IN3")
		(18 "In8.Cu" signal "GND2")
		(20 "In9.Cu" signal "IN4")
		(22 "In10.Cu" signal "GND3")
		(2 "B.Cu" signal "BOTTOM")
		(9 "F.Adhes" user "F.Adhesive")
		(11 "B.Adhes" user "B.Adhesive")
		(13 "F.Paste" user "Package Geometry/Pastemask Top")
		(15 "B.Paste" user "Package Geometry/Pastemask Bottom")
		(5 "F.SilkS" user "Ref Des/Silkscreen Top")
		(7 "B.SilkS" user "Ref Des/Silkscreen Bottom")
		(1 "F.Mask" user "Board Geometry/Soldermask Top")
		(3 "B.Mask" user "Board Geometry/Soldermask Bottom")
		(17 "Dwgs.User" user "User.Drawings")
		(19 "Cmts.User" user "User.Comments")
		(21 "Eco1.User" user "User.Eco1")
		(23 "Eco2.User" user "User.Eco2")
		(25 "Edge.Cuts" user "Board Geometry/Outline")
		(27 "Margin" user)
		(31 "F.CrtYd" user "Package Geometry/Place Bound Top")
		(29 "B.CrtYd" user "Package Geometry/Place Bound Bottom")
		(35 "F.Fab" user "Ref Des/Assembly Top")
		(33 "B.Fab" user "Ref Des/Assembly Bottom")
	)
	(footprint ""
		(layer "F.Cu")
		(at 77.851 -79.121)
		(property "Reference" "C227"
			(at 0 0 0)
			(layer "F.SilkS")
			(hide yes)
			(effects
				(font
					(size 1.27 1.27)
				)
			)
		)
		(property "Value" ""
			(at 0 0 0)
			(layer "F.Fab")
			(effects
				(font
					(size 1.27 1.27)
				)
			)
		)
		(duplicate_pad_numbers_are_jumpers no)
		(fp_line
			(start -0.7874 -0.4064)
			(end 0.7874 -0.4064)
			(stroke
				(width 0.1524)
				(type default)
			)
			(layer "F.SilkS")
		)
		(fp_line
			(start -0.7874 0.4064)
			(end -0.7874 -0.4064)
			(stroke
				(width 0.1524)
				(type default)
			)
			(layer "F.SilkS")
		)
		(fp_line
			(start 0.7874 -0.4064)
			(end 0.7874 0.4064)
			(stroke
				(width 0.1524)
				(type default)
			)
			(layer "F.SilkS")
		)
		(fp_line
			(start 0.7874 0.4064)
			(end -0.7874 0.4064)
			(stroke
				(width 0.1524)
				(type default)
			)
			(layer "F.SilkS")
		)
		(fp_line
			(start -0.67945 -0.305054)
			(end -0.12065 -0.305054)
			(stroke
				(width 0.1)
				(type default)
			)
			(layer "F.Fab")
		)
		(fp_line
			(start -0.67945 0.3048)
			(end -0.67945 -0.305054)
			(stroke
				(width 0.1)
				(type default)
			)
			(layer "F.Fab")
		)
		(fp_line
			(start -0.12065 -0.305054)
			(end -0.12065 -0.2794)
			(stroke
				(width 0.1)
				(type default)
			)
			(layer "F.Fab")
		)
		(fp_line
			(start -0.12065 -0.2794)
			(end 0.12065 -0.2794)
			(stroke
				(width 0.1)
				(type default)
			)
			(layer "F.Fab")
		)
		(fp_line
			(start -0.12065 0.2794)
			(end -0.12065 0.3048)
			(stroke
				(width 0.1)
				(type default)
			)
			(layer "F.Fab")
		)
		(fp_line
			(start -0.12065 0.3048)
			(end -0.67945 0.3048)
			(stroke
				(width 0.1)
				(type default)
			)
			(layer "F.Fab")
		)
		(fp_line
			(start 0.120396 0.2794)
			(end -0.12065 0.2794)
			(stroke
				(width 0.1)
				(type default)
			)
			(layer "F.Fab")
		)
		(fp_line
			(start 0.120396 0.3048)
			(end 0.120396 0.2794)
			(stroke
				(width 0.1)
				(type default)
			)
			(layer "F.Fab")
		)
		(fp_line
			(start 0.12065 -0.3048)
			(end 0.67945 -0.3048)
			(stroke
				(width 0.1)
				(type default)
			)
			(layer "F.Fab")
		)
		(fp_line
			(start 0.12065 -0.2794)
			(end 0.12065 -0.3048)
			(stroke
				(width 0.1)
				(type default)
			)
			(layer "F.Fab")
		)
		(fp_line
			(start 0.67945 -0.3048)
			(end 0.67945 0.3048)
			(stroke
				(width 0.1)
				(type default)
			)
			(layer "F.Fab")
		)
		(fp_line
			(start 0.67945 0.3048)
			(end 0.120396 0.3048)
			(stroke
				(width 0.1)
				(type default)
			)
			(layer "F.Fab")
		)
		(pad "1" smd circle
			(at -0.40005 0)
			(size 0 0)
			(layers "F.Cu" "F.Mask" "F.Paste")
			(net "P3V3_LDO")
		)
		(pad "2" smd circle
			(at 0.40005 0)
			(size 0 0)
			(layers "F.Cu" "F.Mask" "F.Paste")
			(net "GND")
		)
	)
	(footprint ""
		(layer "F.Cu")
		(at 11.783568 -50.110898 -90)
		(property "Reference" "PR527"
			(at 0 0 270)
			(layer "F.SilkS")
			(hide yes)
			(effects
				(font
					(size 1.27 1.27)
				)
			)
		)
		(property "Value" ""
			(at 0 0 270)
			(layer "F.Fab")
			(effects
				(font
					(size 1.27 1.27)
				)
			)
		)
		(duplicate_pad_numbers_are_jumpers no)
		(fp_line
			(start -0.7874 0.4064)
			(end -0.7874 -0.4064)
			(stroke
				(width 0.1524)
				(type default)
			)
			(layer "F.SilkS")
		)
		(fp_line
			(start 0.7874 0.4064)
			(end -0.7874 0.4064)
			(stroke
				(width 0.1524)
				(type default)
			)
			(layer "F.SilkS")
		)
		(fp_line
			(start -0.7874 -0.4064)
			(end 0.7874 -0.4064)
			(stroke
				(width 0.1524)
				(type default)
			)
			(layer "F.SilkS")
		)
		(fp_line
			(start 0.7874 -0.4064)
			(end 0.7874 0.4064)
			(stroke
				(width 0.1524)
				(type default)
			)
			(layer "F.SilkS")
		)
		(fp_line
			(start -0.67945 0.3048)
			(end -0.67945 -0.305054)
			(stroke
				(width 0.1)
				(type default)
			)
			(layer "F.Fab")
		)
		(fp_line
			(start -0.12065 0.3048)
			(end -0.67945 0.3048)
			(stroke
				(width 0.1)
				(type default)
			)
			(layer "F.Fab")
		)
		(fp_line
			(start 0.120396 0.3048)
			(end 0.120396 0.2794)
			(stroke
				(width 0.1)
				(type default)
			)
			(layer "F.Fab")
		)
		(fp_line
			(start 0.67945 0.3048)
			(end 0.120396 0.3048)
			(stroke
				(width 0.1)
				(type default)
			)
			(layer "F.Fab")
		)
		(fp_line
			(start -0.12065 0.2794)
			(end -0.12065 0.3048)
			(stroke
				(width 0.1)
				(type default)
			)
			(layer "F.Fab")
		)
		(fp_line
			(start 0.120396 0.2794)
			(end -0.12065 0.2794)
			(stroke
				(width 0.1)
				(type default)
			)
			(layer "F.Fab")
		)
		(fp_line
			(start -0.12065 -0.2794)
			(end 0.12065 -0.2794)
			(stroke
				(width 0.1)
				(type default)
			)
			(layer "F.Fab")
		)
		(fp_line
			(start 0.12065 -0.2794)
			(end 0.12065 -0.3048)
			(stroke
				(width 0.1)
				(type default)
			)
			(layer "F.Fab")
		)
		(fp_line
			(start 0.12065 -0.3048)
			(end 0.67945 -0.3048)
			(stroke
				(width 0.1)
				(type default)
			)
			(layer "F.Fab")
		)
		(fp_line
			(start 0.67945 -0.3048)
			(end 0.67945 0.3048)
			(stroke
				(width 0.1)
				(type default)
			)
			(layer "F.Fab")
		)
		(fp_line
			(start -0.67945 -0.305054)
			(end -0.12065 -0.305054)
			(stroke
				(width 0.1)
				(type default)
			)
			(layer "F.Fab")
		)
		(fp_line
			(start -0.12065 -0.305054)
			(end -0.12065 -0.2794)
			(stroke
				(width 0.1)
				(type default)
			)
			(layer "F.Fab")
		)
		(pad "1" smd circle
			(at -0.40005 0 270)
			(size 0 0)
			(layers "F.Cu" "F.Mask" "F.Paste")
			(net "P5V_AUX_FB")
		)
		(pad "2" smd circle
			(at 0.40005 0 270)
			(size 0 0)
			(layers "F.Cu" "F.Mask" "F.Paste")
			(net "P5V_AUX")
		)
	)
)
